(kicad_pcb
	(version 20260206)
	(generator "pcbnew")
	(generator_version "10.0")
	(general
		(thickness 1.6)
		(legacy_teardrops no)
	)
	(paper "A4")
	(title_block
		(title "Bryce Canyon_SCC_16316-1_OCP.brd")
		(comment 1 "Bryce Canyon / footprints 873-879 of 1561")
	)
	(layers
		(0 "F.Cu" signal "TOP")
		(4 "In1.Cu" signal "L2GND")
		(6 "In2.Cu" signal "L3")
		(8 "In3.Cu" signal "L4VCC")
		(10 "In4.Cu" signal "L5VCC")
		(12 "In5.Cu" signal "L6")
		(14 "In6.Cu" signal "L7GND")
		(2 "B.Cu" signal "BOTTOM")
		(9 "F.Adhes" user "F.Adhesive")
		(11 "B.Adhes" user "B.Adhesive")
		(13 "F.Paste" user "Package Geometry/Pastemask Top")
		(15 "B.Paste" user "Package Geometry/Pastemask Bottom")
		(5 "F.SilkS" user "Ref Des/Silkscreen Top")
		(7 "B.SilkS" user "Ref Des/Silkscreen Bottom")
		(1 "F.Mask" user "Board Geometry/Soldermask Top")
		(3 "B.Mask" user "Board Geometry/Soldermask Bottom")
		(17 "Dwgs.User" user "User.Drawings")
		(19 "Cmts.User" user "User.Comments")
		(21 "Eco1.User" user "User.Eco1")
		(23 "Eco2.User" user "User.Eco2")
		(25 "Edge.Cuts" user "Board Geometry/Outline")
		(27 "Margin" user)
		(31 "F.CrtYd" user "Package Geometry/Place Bound Top")
		(29 "B.CrtYd" user "Package Geometry/Place Bound Bottom")
		(35 "F.Fab" user "Ref Des/Assembly Top")
		(33 "B.Fab" user "Ref Des/Assembly Bottom")
	)
	(footprint ""
		(layer "B.Cu")
		(at 136.1694 -76.1492 -90)
		(property "Reference" "C8"
			(at 0 0 90)
			(layer "B.SilkS")
			(hide yes)
			(effects
				(font
					(size 1.27 1.27)
				)
				(justify mirror)
			)
		)
		(property "Value" "SCD01U16V1KX-GP"
			(at 2.8321 -1.7399 270)
			(unlocked yes)
			(layer "B.Fab")
			(hide yes)
			(effects
				(font
					(size 1.016 1.016)
					(thickness 0.1524)
				)
				(justify mirror)
			)
		)
		(property "Device Type" "C0201H13"
			(at 2.8321 -3.2639 270)
			(unlocked yes)
			(layer "B.Fab")
			(hide yes)
			(effects
				(font
					(size 1.016 1.016)
					(thickness 0.1524)
				)
				(justify mirror)
			)
		)
		(duplicate_pad_numbers_are_jumpers no)
		(fp_rect
			(start 0.2794 0.6477)
			(end -0.2794 -0.6477)
			(stroke
				(width 0)
				(type default)
			)
			(fill no)
			(layer "B.CrtYd")
		)
		(fp_rect
			(start 0.2794 0.6477)
			(end -0.2794 -0.6477)
			(stroke
				(width 0)
				(type default)
			)
			(fill no)
			(layer "B.Fab")
		)
		(pad "1" smd custom
			(at 0 -0.2794 90)
			(size 0.0762 0.0762)
			(layers "B.Cu" "B.Mask" "B.Paste")
			(net "PHY_CONN_TO_EXP_8_DN")
			(options
				(clearance outline)
				(anchor circle)
			)
			(primitives
				(gr_poly
					(pts
						(arc
							(start 0.1524 0.127)
							(mid 0.137521 0.162921)
							(end 0.1016 0.1778)
						)
						(arc
							(start -0.1016 0.1778)
							(mid -0.137521 0.162921)
							(end -0.1524 0.127)
						)
						(arc
							(start -0.1524 -0.127)
							(mid -0.137521 -0.162921)
							(end -0.1016 -0.1778)
						)
						(arc
							(start 0.1016 -0.1778)
							(mid 0.137521 -0.162921)
							(end 0.1524 -0.127)
						)
					)
					(width 0)
					(fill yes)
				)
			)
		)
		(pad "2" smd custom
			(at 0 0.2794 90)
			(size 0.0762 0.0762)
			(layers "B.Cu" "B.Mask" "B.Paste")
			(net "PHY_CONN_TO_EXP_C_8_DN")
			(options
				(clearance outline)
				(anchor circle)
			)
			(primitives
				(gr_poly
					(pts
						(arc
							(start 0.1524 0.127)
							(mid 0.137521 0.162921)
							(end 0.1016 0.1778)
						)
						(arc
							(start -0.1016 0.1778)
							(mid -0.137521 0.162921)
							(end -0.1524 0.127)
						)
						(arc
							(start -0.1524 -0.127)
							(mid -0.137521 -0.162921)
							(end -0.1016 -0.1778)
						)
						(arc
							(start 0.1016 -0.1778)
							(mid 0.137521 -0.162921)
							(end 0.1524 -0.127)
						)
					)
					(width 0)
					(fill yes)
				)
			)
		)
	)
	(footprint ""
		(layer "B.Cu")
		(at 119.117872 -70.427596 180)
		(property "Reference" "C188"
			(at 0 0 0)
			(layer "B.SilkS")
			(hide yes)
			(effects
				(font
					(size 1.27 1.27)
				)
				(justify mirror)
			)
		)
		(property "Value" "SC1KP25V1KX-GP"
			(at 2.8321 -1.7399 180)
			(unlocked yes)
			(layer "B.Fab")
			(hide yes)
			(effects
				(font
					(size 1.016 1.016)
					(thickness 0.1524)
				)
				(justify mirror)
			)
		)
		(property "Device Type" "C0201H13"
			(at 2.8321 -3.2639 180)
			(unlocked yes)
			(layer "B.Fab")
			(hide yes)
			(effects
				(font
					(size 1.016 1.016)
					(thickness 0.1524)
				)
				(justify mirror)
			)
		)
		(duplicate_pad_numbers_are_jumpers no)
		(fp_rect
			(start 0.2794 0.6477)
			(end -0.2794 -0.6477)
			(stroke
				(width 0)
				(type default)
			)
			(fill no)
			(layer "B.CrtYd")
		)
		(fp_rect
			(start 0.2794 0.6477)
			(end -0.2794 -0.6477)
			(stroke
				(width 0)
				(type default)
			)
			(fill no)
			(layer "B.Fab")
		)
		(pad "1" smd custom
			(at 0 -0.2794)
			(size 0.0762 0.0762)
			(layers "B.Cu" "B.Mask" "B.Paste")
			(net "P0V9")
			(options
				(clearance outline)
				(anchor circle)
			)
			(primitives
				(gr_poly
					(pts
						(arc
							(start 0.1524 0.127)
							(mid 0.137521 0.162921)
							(end 0.1016 0.1778)
						)
						(arc
							(start -0.1016 0.1778)
							(mid -0.137521 0.162921)
							(end -0.1524 0.127)
						)
						(arc
							(start -0.1524 -0.127)
							(mid -0.137521 -0.162921)
							(end -0.1016 -0.1778)
						)
						(arc
							(start 0.1016 -0.1778)
							(mid 0.137521 -0.162921)
							(end 0.1524 -0.127)
						)
					)
					(width 0)
					(fill yes)
				)
			)
		)
		(pad "2" smd custom
			(at 0 0.2794)
			(size 0.0762 0.0762)
			(layers "B.Cu" "B.Mask" "B.Paste")
			(net "GND")
			(options
				(clearance outline)
				(anchor circle)
			)
			(primitives
				(gr_poly
					(pts
						(arc
							(start 0.1524 0.127)
							(mid 0.137521 0.162921)
							(end 0.1016 0.1778)
						)
						(arc
							(start -0.1016 0.1778)
							(mid -0.137521 0.162921)
							(end -0.1524 0.127)
						)
						(arc
							(start -0.1524 -0.127)
							(mid -0.137521 -0.162921)
							(end -0.1016 -0.1778)
						)
						(arc
							(start 0.1016 -0.1778)
							(mid 0.137521 -0.162921)
							(end 0.1524 -0.127)
						)
					)
					(width 0)
					(fill yes)
				)
			)
		)
	)
	(footprint ""
		(layer "B.Cu")
		(at 202.820778 -33.170622 -90)
		(property "Reference" "R280"
			(at 0 0 90)
			(layer "B.SilkS")
			(hide yes)
			(effects
				(font
					(size 1.27 1.27)
				)
				(justify mirror)
			)
		)
		(property "Value" "10R2F-L-GP"
			(at -0.064008 -3.993896 270)
			(unlocked yes)
			(layer "B.Fab")
			(hide yes)
			(effects
				(font
					(size 1.016 1.016)
					(thickness 0.1524)
				)
				(justify mirror)
			)
		)
		(property "Device Type" "R402H14"
			(at -0.064008 -5.517896 270)
			(unlocked yes)
			(layer "B.Fab")
			(hide yes)
			(effects
				(font
					(size 1.016 1.016)
					(thickness 0.1524)
				)
				(justify mirror)
			)
		)
		(duplicate_pad_numbers_are_jumpers no)
		(fp_line
			(start -0.508 -0.9398)
			(end 0.508 -0.9398)
			(stroke
				(width 0.1524)
				(type default)
			)
			(layer "B.SilkS")
		)
		(fp_line
			(start 0.508 -0.9398)
			(end 0.508 0.9398)
			(stroke
				(width 0.1524)
				(type default)
			)
			(layer "B.SilkS")
		)
		(fp_rect
			(start 0.508 0.9398)
			(end -0.508 -0.9398)
			(stroke
				(width 0)
				(type default)
			)
			(fill no)
			(layer "B.CrtYd")
		)
		(fp_rect
			(start 0.508 0.9398)
			(end -0.508 -0.9398)
			(stroke
				(width 0)
				(type default)
			)
			(fill no)
			(layer "B.Fab")
		)
		(pad "1" smd custom
			(at 0 -0.4445 90)
			(size 0.1397 0.1397)
			(layers "B.Cu" "B.Mask" "B.Paste")
			(net "P1V8_C")
			(options
				(clearance outline)
				(anchor circle)
			)
			(primitives
				(gr_poly
					(pts
						(arc
							(start -0.1778 0.2794)
							(mid -0.249642 0.249642)
							(end -0.2794 0.1778)
						)
						(arc
							(start -0.2794 -0.1778)
							(mid -0.249642 -0.249642)
							(end -0.1778 -0.2794)
						)
						(arc
							(start 0.1778 -0.2794)
							(mid 0.249642 -0.249642)
							(end 0.2794 -0.1778)
						)
						(arc
							(start 0.2794 0.1778)
							(mid 0.249642 0.249642)
							(end 0.1778 0.2794)
						)
					)
					(width 0)
					(fill yes)
				)
			)
		)
		(pad "2" smd custom
			(at 0 0.4445 90)
			(size 0.1397 0.1397)
			(layers "B.Cu" "B.Mask" "B.Paste")
			(net "PLL_VDD")
			(options
				(clearance outline)
				(anchor circle)
			)
			(primitives
				(gr_poly
					(pts
						(arc
							(start -0.1778 0.2794)
							(mid -0.249642 0.249642)
							(end -0.2794 0.1778)
						)
						(arc
							(start -0.2794 -0.1778)
							(mid -0.249642 -0.249642)
							(end -0.1778 -0.2794)
						)
						(arc
							(start 0.1778 -0.2794)
							(mid 0.249642 -0.249642)
							(end 0.2794 -0.1778)
						)
						(arc
							(start 0.2794 0.1778)
							(mid 0.249642 0.249642)
							(end 0.1778 0.2794)
						)
					)
					(width 0)
					(fill yes)
				)
			)
		)
	)
	(footprint ""
		(layer "B.Cu")
		(at 176.22139 -40.268144 90)
		(property "Reference" "C430"
			(at 0 0 90)
			(layer "B.SilkS")
			(hide yes)
			(effects
				(font
					(size 1.27 1.27)
				)
				(justify mirror)
			)
		)
		(property "Value" "SCD1U6D3V1KX-GP"
			(at 2.8321 -1.7399 90)
			(unlocked yes)
			(layer "B.Fab")
			(hide yes)
			(effects
				(font
					(size 1.016 1.016)
					(thickness 0.1524)
				)
				(justify mirror)
			)
		)
		(property "Device Type" "C0201H13"
			(at 2.8321 -3.2639 90)
			(unlocked yes)
			(layer "B.Fab")
			(hide yes)
			(effects
				(font
					(size 1.016 1.016)
					(thickness 0.1524)
				)
				(justify mirror)
			)
		)
		(duplicate_pad_numbers_are_jumpers no)
		(fp_rect
			(start 0.2794 0.6477)
			(end -0.2794 -0.6477)
			(stroke
				(width 0)
				(type default)
			)
			(fill no)
			(layer "B.CrtYd")
		)
		(fp_rect
			(start 0.2794 0.6477)
			(end -0.2794 -0.6477)
			(stroke
				(width 0)
				(type default)
			)
			(fill no)
			(layer "B.Fab")
		)
		(pad "1" smd custom
			(at 0 -0.2794 270)
			(size 0.0762 0.0762)
			(layers "B.Cu" "B.Mask" "B.Paste")
			(net "P0V975")
			(options
				(clearance outline)
				(anchor circle)
			)
			(primitives
				(gr_poly
					(pts
						(arc
							(start 0.1524 0.127)
							(mid 0.137521 0.162921)
							(end 0.1016 0.1778)
						)
						(arc
							(start -0.1016 0.1778)
							(mid -0.137521 0.162921)
							(end -0.1524 0.127)
						)
						(arc
							(start -0.1524 -0.127)
							(mid -0.137521 -0.162921)
							(end -0.1016 -0.1778)
						)
						(arc
							(start 0.1016 -0.1778)
							(mid 0.137521 -0.162921)
							(end 0.1524 -0.127)
						)
					)
					(width 0)
					(fill yes)
				)
			)
		)
		(pad "2" smd custom
			(at 0 0.2794 270)
			(size 0.0762 0.0762)
			(layers "B.Cu" "B.Mask" "B.Paste")
			(net "GND")
			(options
				(clearance outline)
				(anchor circle)
			)
			(primitives
				(gr_poly
					(pts
						(arc
							(start 0.1524 0.127)
							(mid 0.137521 0.162921)
							(end 0.1016 0.1778)
						)
						(arc
							(start -0.1016 0.1778)
							(mid -0.137521 0.162921)
							(end -0.1524 0.127)
						)
						(arc
							(start -0.1524 -0.127)
							(mid -0.137521 -0.162921)
							(end -0.1016 -0.1778)
						)
						(arc
							(start 0.1016 -0.1778)
							(mid 0.137521 -0.162921)
							(end 0.1524 -0.127)
						)
					)
					(width 0)
					(fill yes)
				)
			)
		)
	)
	(footprint ""
		(layer "B.Cu")
		(at 127.5588 -92.026486)
		(property "Reference" "R110"
			(at 0 0 0)
			(layer "B.SilkS")
			(hide yes)
			(effects
				(font
					(size 1.27 1.27)
				)
				(justify mirror)
			)
		)
		(property "Value" "4K75R2F-1-GP"
			(at -0.064008 -3.993896 0)
			(unlocked yes)
			(layer "B.Fab")
			(hide yes)
			(effects
				(font
					(size 1.016 1.016)
					(thickness 0.1524)
				)
				(justify mirror)
			)
		)
		(property "Device Type" "R402H16"
			(at -0.064008 -5.517896 0)
			(unlocked yes)
			(layer "B.Fab")
			(hide yes)
			(effects
				(font
					(size 1.016 1.016)
					(thickness 0.1524)
				)
				(justify mirror)
			)
		)
		(duplicate_pad_numbers_are_jumpers no)
		(fp_line
			(start -0.508 -0.9398)
			(end 0.508 -0.9398)
			(stroke
				(width 0.1524)
				(type default)
			)
			(layer "B.SilkS")
		)
		(fp_line
			(start 0.508 -0.9398)
			(end 0.508 0.9398)
			(stroke
				(width 0.1524)
				(type default)
			)
			(layer "B.SilkS")
		)
		(fp_rect
			(start 0.508 0.9398)
			(end -0.508 -0.9398)
			(stroke
				(width 0)
				(type default)
			)
			(fill no)
			(layer "B.CrtYd")
		)
		(fp_rect
			(start 0.508 0.9398)
			(end -0.508 -0.9398)
			(stroke
				(width 0)
				(type default)
			)
			(fill no)
			(layer "B.Fab")
		)
		(pad "1" smd custom
			(at 0 -0.4445 180)
			(size 0.1397 0.1397)
			(layers "B.Cu" "B.Mask" "B.Paste")
			(net "GND")
			(options
				(clearance outline)
				(anchor circle)
			)
			(primitives
				(gr_poly
					(pts
						(arc
							(start -0.1778 0.2794)
							(mid -0.249642 0.249642)
							(end -0.2794 0.1778)
						)
						(arc
							(start -0.2794 -0.1778)
							(mid -0.249642 -0.249642)
							(end -0.1778 -0.2794)
						)
						(arc
							(start 0.1778 -0.2794)
							(mid 0.249642 -0.249642)
							(end 0.2794 -0.1778)
						)
						(arc
							(start 0.2794 0.1778)
							(mid 0.249642 0.249642)
							(end 0.1778 0.2794)
						)
					)
					(width 0)
					(fill yes)
				)
			)
		)
		(pad "2" smd custom
			(at 0 0.4445 180)
			(size 0.1397 0.1397)
			(layers "B.Cu" "B.Mask" "B.Paste")
			(net "LSI_EFUSE")
			(options
				(clearance outline)
				(anchor circle)
			)
			(primitives
				(gr_poly
					(pts
						(arc
							(start -0.1778 0.2794)
							(mid -0.249642 0.249642)
							(end -0.2794 0.1778)
						)
						(arc
							(start -0.2794 -0.1778)
							(mid -0.249642 -0.249642)
							(end -0.1778 -0.2794)
						)
						(arc
							(start 0.1778 -0.2794)
							(mid 0.249642 -0.249642)
							(end 0.2794 -0.1778)
						)
						(arc
							(start 0.2794 0.1778)
							(mid 0.249642 0.249642)
							(end 0.1778 0.2794)
						)
					)
					(width 0)
					(fill yes)
				)
			)
		)
	)
	(footprint ""
		(layer "B.Cu")
		(at 90.988388 -74.762614)
		(property "Reference" "R154"
			(at 0 0 0)
			(layer "B.SilkS")
			(hide yes)
			(effects
				(font
					(size 1.27 1.27)
				)
				(justify mirror)
			)
		)
		(property "Value" "10R2F-L-GP"
			(at -0.064008 -3.993896 0)
			(unlocked yes)
			(layer "B.Fab")
			(hide yes)
			(effects
				(font
					(size 1.016 1.016)
					(thickness 0.1524)
				)
				(justify mirror)
			)
		)
		(property "Device Type" "R402H14"
			(at -0.064008 -5.517896 0)
			(unlocked yes)
			(layer "B.Fab")
			(hide yes)
			(effects
				(font
					(size 1.016 1.016)
					(thickness 0.1524)
				)
				(justify mirror)
			)
		)
		(duplicate_pad_numbers_are_jumpers no)
		(fp_line
			(start -0.508 -0.9398)
			(end 0.508 -0.9398)
			(stroke
				(width 0.1524)
				(type default)
			)
			(layer "B.SilkS")
		)
		(fp_line
			(start 0.508 -0.9398)
			(end 0.508 0.9398)
			(stroke
				(width 0.1524)
				(type default)
			)
			(layer "B.SilkS")
		)
		(fp_rect
			(start 0.508 0.9398)
			(end -0.508 -0.9398)
			(stroke
				(width 0)
				(type default)
			)
			(fill no)
			(layer "B.CrtYd")
		)
		(fp_rect
			(start 0.508 0.9398)
			(end -0.508 -0.9398)
			(stroke
				(width 0)
				(type default)
			)
			(fill no)
			(layer "B.Fab")
		)
		(pad "1" smd custom
			(at 0 -0.4445 180)
			(size 0.1397 0.1397)
			(layers "B.Cu" "B.Mask" "B.Paste")
			(net "P0V9")
			(options
				(clearance outline)
				(anchor circle)
			)
			(primitives
				(gr_poly
					(pts
						(arc
							(start -0.1778 0.2794)
							(mid -0.249642 0.249642)
							(end -0.2794 0.1778)
						)
						(arc
							(start -0.2794 -0.1778)
							(mid -0.249642 -0.249642)
							(end -0.1778 -0.2794)
						)
						(arc
							(start 0.1778 -0.2794)
							(mid 0.249642 -0.249642)
							(end 0.2794 -0.1778)
						)
						(arc
							(start 0.2794 0.1778)
							(mid 0.249642 0.249642)
							(end 0.1778 0.2794)
						)
					)
					(width 0)
					(fill yes)
				)
			)
		)
		(pad "2" smd custom
			(at 0 0.4445 180)
			(size 0.1397 0.1397)
			(layers "B.Cu" "B.Mask" "B.Paste")
			(net "XTAL_VDDA09")
			(options
				(clearance outline)
				(anchor circle)
			)
			(primitives
				(gr_poly
					(pts
						(arc
							(start -0.1778 0.2794)
							(mid -0.249642 0.249642)
							(end -0.2794 0.1778)
						)
						(arc
							(start -0.2794 -0.1778)
							(mid -0.249642 -0.249642)
							(end -0.1778 -0.2794)
						)
						(arc
							(start 0.1778 -0.2794)
							(mid 0.249642 -0.249642)
							(end 0.2794 -0.1778)
						)
						(arc
							(start 0.2794 0.1778)
							(mid 0.249642 0.249642)
							(end 0.1778 0.2794)
						)
					)
					(width 0)
					(fill yes)
				)
			)
		)
	)
	(footprint ""
		(layer "B.Cu")
		(at 122.4788 -63.4873 -90)
		(property "Reference" "C536"
			(at 0 0 90)
			(layer "B.SilkS")
			(hide yes)
			(effects
				(font
					(size 1.27 1.27)
				)
				(justify mirror)
			)
		)
		(property "Value" "SCD1U6D3V1KX-GP"
			(at 2.8321 -1.7399 270)
			(unlocked yes)
			(layer "B.Fab")
			(hide yes)
			(effects
				(font
					(size 1.016 1.016)
					(thickness 0.1524)
				)
				(justify mirror)
			)
		)
		(property "Device Type" "C0201H13"
			(at 2.8321 -3.2639 270)
			(unlocked yes)
			(layer "B.Fab")
			(hide yes)
			(effects
				(font
					(size 1.016 1.016)
					(thickness 0.1524)
				)
				(justify mirror)
			)
		)
		(duplicate_pad_numbers_are_jumpers no)
		(fp_rect
			(start 0.2794 0.6477)
			(end -0.2794 -0.6477)
			(stroke
				(width 0)
				(type default)
			)
			(fill no)
			(layer "B.CrtYd")
		)
		(fp_rect
			(start 0.2794 0.6477)
			(end -0.2794 -0.6477)
			(stroke
				(width 0)
				(type default)
			)
			(fill no)
			(layer "B.Fab")
		)
		(pad "1" smd custom
			(at 0 -0.2794 90)
			(size 0.0762 0.0762)
			(layers "B.Cu" "B.Mask" "B.Paste")
			(net "GB_VDDA")
			(options
				(clearance outline)
				(anchor circle)
			)
			(primitives
				(gr_poly
					(pts
						(arc
							(start 0.1524 0.127)
							(mid 0.137521 0.162921)
							(end 0.1016 0.1778)
						)
						(arc
							(start -0.1016 0.1778)
							(mid -0.137521 0.162921)
							(end -0.1524 0.127)
						)
						(arc
							(start -0.1524 -0.127)
							(mid -0.137521 -0.162921)
							(end -0.1016 -0.1778)
						)
						(arc
							(start 0.1016 -0.1778)
							(mid 0.137521 -0.162921)
							(end 0.1524 -0.127)
						)
					)
					(width 0)
					(fill yes)
				)
			)
		)
		(pad "2" smd custom
			(at 0 0.2794 90)
			(size 0.0762 0.0762)
			(layers "B.Cu" "B.Mask" "B.Paste")
			(net "GND")
			(options
				(clearance outline)
				(anchor circle)
			)
			(primitives
				(gr_poly
					(pts
						(arc
							(start 0.1524 0.127)
							(mid 0.137521 0.162921)
							(end 0.1016 0.1778)
						)
						(arc
							(start -0.1016 0.1778)
							(mid -0.137521 0.162921)
							(end -0.1524 0.127)
						)
						(arc
							(start -0.1524 -0.127)
							(mid -0.137521 -0.162921)
							(end -0.1016 -0.1778)
						)
						(arc
							(start 0.1016 -0.1778)
							(mid 0.137521 -0.162921)
							(end 0.1524 -0.127)
						)
					)
					(width 0)
					(fill yes)
				)
			)
		)
	)
)
